# S9S_MB_2U (Grand Teton) — schematic netlist excerpt (pin names and nets, part order shuffled) for the footprints in the layout excerpt that follows; sources: Cadence DE-HDL packaged netlist, KiCad conversion of 03242023_DA0F0TMBIJ0_F0T_Motherboard_J_brd_V01_OCP.brd

PR2519  Q_RES  100 1% EMPTY  pkg 0402LF  page 304 : A = P12V_HSC_ADC_N ; B = P12V_HSC_SENSE1_N
C2020  Q_CAP  0.1UF 25V 10% X7R  pkg 0402  page 172 : A = VSENSE_P12V_INA230_3_INP ; B = VSENSE_P12V_INA230_3_INN

(kicad_pcb
	(version 20260206)
	(generator "pcbnew")
	(generator_version "10.0")
	(general
		(thickness 1.6)
		(legacy_teardrops no)
	)
	(paper "A4")
	(title_block
		(title "03242023_DA0F0TMBIJ0_F0T_Motherboard_J_brd_V01_OCP.brd")
		(comment 1 "Grand Teton / footprints 5229-5230 of 6105")
	)
	(layers
		(0 "F.Cu" signal "TOP")
		(4 "In1.Cu" signal "GND")
		(6 "In2.Cu" signal "IN1")
		(8 "In3.Cu" signal "GND1")
		(10 "In4.Cu" signal "IN2")
		(12 "In5.Cu" signal "GND2")
		(14 "In6.Cu" signal "IN3")
		(16 "In7.Cu" signal "GND3")
		(18 "In8.Cu" signal "VCC")
		(20 "In9.Cu" signal "VCC1")
		(22 "In10.Cu" signal "GND4")
		(24 "In11.Cu" signal "IN4")
		(26 "In12.Cu" signal "GND5")
		(28 "In13.Cu" signal "IN5")
		(30 "In14.Cu" signal "GND6")
		(32 "In15.Cu" signal "IN6")
		(34 "In16.Cu" signal "GND7")
		(2 "B.Cu" signal "BOTTOM")
		(9 "F.Adhes" user "F.Adhesive")
		(11 "B.Adhes" user "B.Adhesive")
		(13 "F.Paste" user "Package Geometry/Pastemask Top")
		(15 "B.Paste" user "Package Geometry/Pastemask Bottom")
		(5 "F.SilkS" user "Ref Des/Silkscreen Top")
		(7 "B.SilkS" user "Ref Des/Silkscreen Bottom")
		(1 "F.Mask" user "Board Geometry/Soldermask Top")
		(3 "B.Mask" user "Board Geometry/Soldermask Bottom")
		(17 "Dwgs.User" user "User.Drawings")
		(19 "Cmts.User" user "User.Comments")
		(21 "Eco1.User" user "User.Eco1")
		(23 "Eco2.User" user "User.Eco2")
		(25 "Edge.Cuts" user "Board Geometry/Outline")
		(27 "Margin" user)
		(31 "F.CrtYd" user "Package Geometry/Place Bound Top")
		(29 "B.CrtYd" user "Package Geometry/Place Bound Bottom")
		(35 "F.Fab" user "Ref Des/Assembly Top")
		(33 "B.Fab" user "Ref Des/Assembly Bottom")
	)
	(footprint ""
		(layer "B.Cu")
		(at 287.448498 -403.031452 90)
		(property "Reference" "PR2519"
			(at 0 0 90)
			(layer "B.SilkS")
			(hide yes)
			(effects
				(font
					(size 1.27 1.27)
				)
				(justify mirror)
			)
		)
		(property "Value" ""
			(at 0 0 90)
			(layer "B.Fab")
			(effects
				(font
					(size 1.27 1.27)
				)
				(justify mirror)
			)
		)
		(duplicate_pad_numbers_are_jumpers no)
		(fp_line
			(start 0.7874 -0.4064)
			(end -0.7874 -0.4064)
			(stroke
				(width 0.1524)
				(type default)
			)
			(layer "B.SilkS")
		)
		(fp_line
			(start -0.7874 -0.4064)
			(end -0.7874 0.4064)
			(stroke
				(width 0.1524)
				(type default)
			)
			(layer "B.SilkS")
		)
		(fp_line
			(start 0.7874 0.4064)
			(end 0.7874 -0.4064)
			(stroke
				(width 0.1524)
				(type default)
			)
			(layer "B.SilkS")
		)
		(fp_line
			(start -0.7874 0.4064)
			(end 0.7874 0.4064)
			(stroke
				(width 0.1524)
				(type default)
			)
			(layer "B.SilkS")
		)
		(fp_line
			(start 0.67945 -0.305054)
			(end 0.12065 -0.305054)
			(stroke
				(width 0.1)
				(type default)
			)
			(layer "B.Fab")
		)
		(fp_line
			(start 0.12065 -0.305054)
			(end 0.12065 -0.2794)
			(stroke
				(width 0.1)
				(type default)
			)
			(layer "B.Fab")
		)
		(fp_line
			(start -0.12065 -0.3048)
			(end -0.67945 -0.3048)
			(stroke
				(width 0.1)
				(type default)
			)
			(layer "B.Fab")
		)
		(fp_line
			(start -0.67945 -0.3048)
			(end -0.67945 0.3048)
			(stroke
				(width 0.1)
				(type default)
			)
			(layer "B.Fab")
		)
		(fp_line
			(start 0.12065 -0.2794)
			(end -0.12065 -0.2794)
			(stroke
				(width 0.1)
				(type default)
			)
			(layer "B.Fab")
		)
		(fp_line
			(start -0.12065 -0.2794)
			(end -0.12065 -0.3048)
			(stroke
				(width 0.1)
				(type default)
			)
			(layer "B.Fab")
		)
		(fp_line
			(start 0.12065 0.2794)
			(end 0.12065 0.3048)
			(stroke
				(width 0.1)
				(type default)
			)
			(layer "B.Fab")
		)
		(fp_line
			(start -0.120396 0.2794)
			(end 0.12065 0.2794)
			(stroke
				(width 0.1)
				(type default)
			)
			(layer "B.Fab")
		)
		(fp_line
			(start 0.67945 0.3048)
			(end 0.67945 -0.305054)
			(stroke
				(width 0.1)
				(type default)
			)
			(layer "B.Fab")
		)
		(fp_line
			(start 0.12065 0.3048)
			(end 0.67945 0.3048)
			(stroke
				(width 0.1)
				(type default)
			)
			(layer "B.Fab")
		)
		(fp_line
			(start -0.120396 0.3048)
			(end -0.120396 0.2794)
			(stroke
				(width 0.1)
				(type default)
			)
			(layer "B.Fab")
		)
		(fp_line
			(start -0.67945 0.3048)
			(end -0.120396 0.3048)
			(stroke
				(width 0.1)
				(type default)
			)
			(layer "B.Fab")
		)
		(pad "1" smd circle
			(at 0.40005 0 270)
			(size 0 0)
			(layers "B.Cu" "B.Mask" "B.Paste")
			(net "P12V_HSC_ADC_N")
		)
		(pad "2" smd circle
			(at -0.40005 0 270)
			(size 0 0)
			(layers "B.Cu" "B.Mask" "B.Paste")
			(net "P12V_HSC_SENSE1_N")
		)
	)
	(footprint ""
		(layer "B.Cu")
		(at 75.745594 -45.536866 90)
		(property "Reference" "C2020"
			(at 0 0 90)
			(layer "B.SilkS")
			(hide yes)
			(effects
				(font
					(size 1.27 1.27)
				)
				(justify mirror)
			)
		)
		(property "Value" ""
			(at 0 0 90)
			(layer "B.Fab")
			(effects
				(font
					(size 1.27 1.27)
				)
				(justify mirror)
			)
		)
		(duplicate_pad_numbers_are_jumpers no)
		(fp_line
			(start 0.7874 -0.4064)
			(end -0.7874 -0.4064)
			(stroke
				(width 0.1524)
				(type default)
			)
			(layer "B.SilkS")
		)
		(fp_line
			(start -0.7874 -0.4064)
			(end -0.7874 0.4064)
			(stroke
				(width 0.1524)
				(type default)
			)
			(layer "B.SilkS")
		)
		(fp_line
			(start 0.7874 0.4064)
			(end 0.7874 -0.4064)
			(stroke
				(width 0.1524)
				(type default)
			)
			(layer "B.SilkS")
		)
		(fp_line
			(start -0.7874 0.4064)
			(end 0.7874 0.4064)
			(stroke
				(width 0.1524)
				(type default)
			)
			(layer "B.SilkS")
		)
		(fp_line
			(start 0.67945 -0.305054)
			(end 0.12065 -0.305054)
			(stroke
				(width 0.1)
				(type default)
			)
			(layer "B.Fab")
		)
		(fp_line
			(start 0.12065 -0.305054)
			(end 0.12065 -0.2794)
			(stroke
				(width 0.1)
				(type default)
			)
			(layer "B.Fab")
		)
		(fp_line
			(start -0.12065 -0.3048)
			(end -0.67945 -0.3048)
			(stroke
				(width 0.1)
				(type default)
			)
			(layer "B.Fab")
		)
		(fp_line
			(start -0.67945 -0.3048)
			(end -0.67945 0.3048)
			(stroke
				(width 0.1)
				(type default)
			)
			(layer "B.Fab")
		)
		(fp_line
			(start 0.12065 -0.2794)
			(end -0.12065 -0.2794)
			(stroke
				(width 0.1)
				(type default)
			)
			(layer "B.Fab")
		)
		(fp_line
			(start -0.12065 -0.2794)
			(end -0.12065 -0.3048)
			(stroke
				(width 0.1)
				(type default)
			)
			(layer "B.Fab")
		)
		(fp_line
			(start 0.12065 0.2794)
			(end 0.12065 0.3048)
			(stroke
				(width 0.1)
				(type default)
			)
			(layer "B.Fab")
		)
		(fp_line
			(start -0.120396 0.2794)
			(end 0.12065 0.2794)
			(stroke
				(width 0.1)
				(type default)
			)
			(layer "B.Fab")
		)
		(fp_line
			(start 0.67945 0.3048)
			(end 0.67945 -0.305054)
			(stroke
				(width 0.1)
				(type default)
			)
			(layer "B.Fab")
		)
		(fp_line
			(start 0.12065 0.3048)
			(end 0.67945 0.3048)
			(stroke
				(width 0.1)
				(type default)
			)
			(layer "B.Fab")
		)
		(fp_line
			(start -0.120396 0.3048)
			(end -0.120396 0.2794)
			(stroke
				(width 0.1)
				(type default)
			)
			(layer "B.Fab")
		)
		(fp_line
			(start -0.67945 0.3048)
			(end -0.120396 0.3048)
			(stroke
				(width 0.1)
				(type default)
			)
			(layer "B.Fab")
		)
		(pad "1" smd circle
			(at 0.40005 0 270)
			(size 0 0)
			(layers "B.Cu" "B.Mask" "B.Paste")
			(net "VSENSE_P12V_INA230_3_INP")
		)
		(pad "2" smd circle
			(at -0.40005 0 270)
			(size 0 0)
			(layers "B.Cu" "B.Mask" "B.Paste")
			(net "VSENSE_P12V_INA230_3_INN")
		)
	)
)
